#ISCELL
  mstr_misc dns *
  *
#ISCELL
  pure_quanta quanta_title_block_c *
  *
#ISCELL
  standard offpage *
  page201_i1
#ISCELL
  pure_quanta_power universal_gnd *
  page201_i10
#CELL
  pure_quanta q_res *
  page201_i11
#CELL
  pure_quanta mpq8633bglec838z *
  page201_i12
#ISCELL
  pure_quanta_power universal_gnd *
  page201_i13
#ISCELL
  pure_quanta_power universal_gnd *
  page201_i14
#CELL
  pure_quanta q_cap *
  page201_i15
#CELL
  pure_quanta q_res *
  page201_i18
#CELL
  pure_quanta q_cap *
  page201_i19
#CELL
  pure_quanta q_cap *
  page201_i20
#CELL
  pure_quanta q_cap *
  page201_i21
#CELL
  pure_quanta q_cap *
  page201_i22
#CELL
  pure_quanta q_cap *
  page201_i23
#CELL
  pure_quanta q_res *
  page201_i24
#ISCELL
  mstr_symbols universal_power *
  page201_i25
#CELL
  pure_quanta q_cap *
  page201_i26
#CELL
  pure_quanta q_res *
  page201_i27
#CELL
  pure_quanta q_inductor *
  page201_i28
#CELL
  pure_quanta q_inductor *
  page201_i3
#ISCELL
  pure_quanta_power p1v0 *
  page201_i35
#CELL
  pure_quanta q_cap *
  page201_i37
#CELL
  pure_quanta q_res *
  page201_i38
#CELL
  pure_quanta q_res *
  page201_i39
#ISCELL
  mstr_symbols p1v0_aux *
  page201_i4
#ISCELL
  standard offpage *
  page201_i40
#ISCELL
  standard offpage *
  page201_i41
#CELL
  pure_quanta q_res *
  page201_i42
#CELL
  pure_quanta q_res *
  page201_i43
#ISCELL
  pure_quanta_power universal_gnd *
  page201_i44
#ISCELL
  pure_quanta_power universal_gnd *
  page201_i45
#CELL
  pure_quanta q_cap *
  page201_i48
#CELL
  pure_quanta q_cap *
  page201_i49
#ISCELL
  pure_quanta_power universal_gnd *
  page201_i5
#CELL
  pure_quanta q_cap *
  page201_i50
#CELL
  pure_quanta q_cap *
  page201_i51
#CELL
  pure_quanta q_cap *
  page201_i52
#CELL
  pure_quanta q_cap *
  page201_i53
#CELL
  pure_quanta q_res *
  page201_i55
#CELL
  pure_quanta q_res *
  page201_i56
#ISCELL
  pure_quanta_power universal_gnd *
  page201_i57
#CELL
  pure_quanta q_capp *
  page201_i59
#CELL
  pure_quanta q_cap *
  page201_i6
#CELL
  pure_quanta q_cap *
  page201_i60
#ISCELL
  pure_quanta_power universal_gnd *
  page201_i61
#CELL
  pure_quanta q_res *
  page201_i62
#ISCELL
  standard offpage *
  page201_i63
#CELL
  pure_quanta q_cap *
  page201_i64
#ISCELL
  pure_quanta_power universal_gnd *
  page201_i65
#ISCELL
  pure_quanta_power universal_gnd *
  page201_i7
#CELL
  pure_quanta q_res *
  page201_i8
#ISCELL
  mstr_symbols universal_power *
  page201_i9
